# S9S_MB_2U (Grand Teton) — schematic netlist excerpt (pin names and nets, part order shuffled) for the footprints in the layout excerpt that follows; sources: Cadence DE-HDL packaged netlist, KiCad conversion of 03242023_DA0F0TMBIJ0_F0T_Motherboard_J_brd_V01_OCP.brd

R2454  Q_RES  33.2 1% CHIP  pkg 0402LF  page 241 : A = SMB_VR_3V3AUX_SDA_R ; B = SMB_VR_3V3AUX_SDA_R2

(kicad_pcb
	(version 20260206)
	(generator "pcbnew")
	(generator_version "10.0")
	(general
		(thickness 1.6)
		(legacy_teardrops no)
	)
	(paper "A4")
	(title_block
		(title "03242023_DA0F0TMBIJ0_F0T_Motherboard_J_brd_V01_OCP.brd")
		(comment 1 "Grand Teton / footprints 532-532 of 6105")
	)
	(layers
		(0 "F.Cu" signal "TOP")
		(4 "In1.Cu" signal "GND")
		(6 "In2.Cu" signal "IN1")
		(8 "In3.Cu" signal "GND1")
		(10 "In4.Cu" signal "IN2")
		(12 "In5.Cu" signal "GND2")
		(14 "In6.Cu" signal "IN3")
		(16 "In7.Cu" signal "GND3")
		(18 "In8.Cu" signal "VCC")
		(20 "In9.Cu" signal "VCC1")
		(22 "In10.Cu" signal "GND4")
		(24 "In11.Cu" signal "IN4")
		(26 "In12.Cu" signal "GND5")
		(28 "In13.Cu" signal "IN5")
		(30 "In14.Cu" signal "GND6")
		(32 "In15.Cu" signal "IN6")
		(34 "In16.Cu" signal "GND7")
		(2 "B.Cu" signal "BOTTOM")
		(9 "F.Adhes" user "F.Adhesive")
		(11 "B.Adhes" user "B.Adhesive")
		(13 "F.Paste" user "Package Geometry/Pastemask Top")
		(15 "B.Paste" user "Package Geometry/Pastemask Bottom")
		(5 "F.SilkS" user "Ref Des/Silkscreen Top")
		(7 "B.SilkS" user "Ref Des/Silkscreen Bottom")
		(1 "F.Mask" user "Board Geometry/Soldermask Top")
		(3 "B.Mask" user "Board Geometry/Soldermask Bottom")
		(17 "Dwgs.User" user "User.Drawings")
		(19 "Cmts.User" user "User.Comments")
		(21 "Eco1.User" user "User.Eco1")
		(23 "Eco2.User" user "User.Eco2")
		(25 "Edge.Cuts" user "Board Geometry/Outline")
		(27 "Margin" user)
		(31 "F.CrtYd" user "Package Geometry/Place Bound Top")
		(29 "B.CrtYd" user "Package Geometry/Place Bound Bottom")
		(35 "F.Fab" user "Ref Des/Assembly Top")
		(33 "B.Fab" user "Ref Des/Assembly Bottom")
	)
	(footprint ""
		(layer "F.Cu")
		(at 33.100518 -122.380502 -90)
		(property "Reference" "R2454"
			(at 0 0 270)
			(layer "F.SilkS")
			(hide yes)
			(effects
				(font
					(size 1.27 1.27)
				)
			)
		)
		(property "Value" ""
			(at 0 0 270)
			(layer "F.Fab")
			(effects
				(font
					(size 1.27 1.27)
				)
			)
		)
		(duplicate_pad_numbers_are_jumpers no)
		(fp_line
			(start -0.7874 0.4064)
			(end -0.7874 -0.4064)
			(stroke
				(width 0.1524)
				(type default)
			)
			(layer "F.SilkS")
		)
		(fp_line
			(start 0.7874 0.4064)
			(end -0.7874 0.4064)
			(stroke
				(width 0.1524)
				(type default)
			)
			(layer "F.SilkS")
		)
		(fp_line
			(start -0.7874 -0.4064)
			(end 0.7874 -0.4064)
			(stroke
				(width 0.1524)
				(type default)
			)
			(layer "F.SilkS")
		)
		(fp_line
			(start 0.7874 -0.4064)
			(end 0.7874 0.4064)
			(stroke
				(width 0.1524)
				(type default)
			)
			(layer "F.SilkS")
		)
		(fp_line
			(start -0.67945 0.3048)
			(end -0.67945 -0.305054)
			(stroke
				(width 0.1)
				(type default)
			)
			(layer "F.Fab")
		)
		(fp_line
			(start -0.12065 0.3048)
			(end -0.67945 0.3048)
			(stroke
				(width 0.1)
				(type default)
			)
			(layer "F.Fab")
		)
		(fp_line
			(start 0.120396 0.3048)
			(end 0.120396 0.2794)
			(stroke
				(width 0.1)
				(type default)
			)
			(layer "F.Fab")
		)
		(fp_line
			(start 0.67945 0.3048)
			(end 0.120396 0.3048)
			(stroke
				(width 0.1)
				(type default)
			)
			(layer "F.Fab")
		)
		(fp_line
			(start -0.12065 0.2794)
			(end -0.12065 0.3048)
			(stroke
				(width 0.1)
				(type default)
			)
			(layer "F.Fab")
		)
		(fp_line
			(start 0.120396 0.2794)
			(end -0.12065 0.2794)
			(stroke
				(width 0.1)
				(type default)
			)
			(layer "F.Fab")
		)
		(fp_line
			(start -0.12065 -0.2794)
			(end 0.12065 -0.2794)
			(stroke
				(width 0.1)
				(type default)
			)
			(layer "F.Fab")
		)
		(fp_line
			(start 0.12065 -0.2794)
			(end 0.12065 -0.3048)
			(stroke
				(width 0.1)
				(type default)
			)
			(layer "F.Fab")
		)
		(fp_line
			(start 0.12065 -0.3048)
			(end 0.67945 -0.3048)
			(stroke
				(width 0.1)
				(type default)
			)
			(layer "F.Fab")
		)
		(fp_line
			(start 0.67945 -0.3048)
			(end 0.67945 0.3048)
			(stroke
				(width 0.1)
				(type default)
			)
			(layer "F.Fab")
		)
		(fp_line
			(start -0.67945 -0.305054)
			(end -0.12065 -0.305054)
			(stroke
				(width 0.1)
				(type default)
			)
			(layer "F.Fab")
		)
		(fp_line
			(start -0.12065 -0.305054)
			(end -0.12065 -0.2794)
			(stroke
				(width 0.1)
				(type default)
			)
			(layer "F.Fab")
		)
		(pad "1" smd circle
			(at -0.40005 0 270)
			(size 0 0)
			(layers "F.Cu" "F.Mask" "F.Paste")
			(net "SMB_VR_3V3AUX_SDA_R")
		)
		(pad "2" smd circle
			(at 0.40005 0 270)
			(size 0 0)
			(layers "F.Cu" "F.Mask" "F.Paste")
			(net "SMB_VR_3V3AUX_SDA_R2")
		)
	)
)
